# S9S_MB_2U (Grand Teton) — schematic netlist excerpt (pin names and nets, part order shuffled) for the footprints in the layout excerpt that follows; sources: Cadence DE-HDL packaged netlist, KiCad conversion of 03242023_DA0F0TMBIJ0_F0T_Motherboard_J_brd_V01_OCP.brd

C1231  Q_CAP  10UF 6.3V 20% X6S  pkg C0402  page 189 : A = P1V05_PCH_AUX ; B = GND

DB15  TDR_3P  EMPTY  pkg TH2  page 309
  GND  = T1_GND
  IO1  = TDR_SE_50_OHM_IN5
  IO2  = TDR_SE_50_OHM_IN5

PR4235  Q_RES  0 5% CHIP  pkg 0402LF  page 278 : A = NC_PVCCD_HV_CPU0_ACSP7 ; B = GND

(kicad_pcb
	(version 20260206)
	(generator "pcbnew")
	(generator_version "10.0")
	(general
		(thickness 1.6)
		(legacy_teardrops no)
	)
	(paper "A4")
	(title_block
		(title "03242023_DA0F0TMBIJ0_F0T_Motherboard_J_brd_V01_OCP.brd")
		(comment 1 "Grand Teton / footprints 6102-6104 of 6105")
	)
	(layers
		(0 "F.Cu" signal "TOP")
		(4 "In1.Cu" signal "GND")
		(6 "In2.Cu" signal "IN1")
		(8 "In3.Cu" signal "GND1")
		(10 "In4.Cu" signal "IN2")
		(12 "In5.Cu" signal "GND2")
		(14 "In6.Cu" signal "IN3")
		(16 "In7.Cu" signal "GND3")
		(18 "In8.Cu" signal "VCC")
		(20 "In9.Cu" signal "VCC1")
		(22 "In10.Cu" signal "GND4")
		(24 "In11.Cu" signal "IN4")
		(26 "In12.Cu" signal "GND5")
		(28 "In13.Cu" signal "IN5")
		(30 "In14.Cu" signal "GND6")
		(32 "In15.Cu" signal "IN6")
		(34 "In16.Cu" signal "GND7")
		(2 "B.Cu" signal "BOTTOM")
		(9 "F.Adhes" user "F.Adhesive")
		(11 "B.Adhes" user "B.Adhesive")
		(13 "F.Paste" user "Package Geometry/Pastemask Top")
		(15 "B.Paste" user "Package Geometry/Pastemask Bottom")
		(5 "F.SilkS" user "Ref Des/Silkscreen Top")
		(7 "B.SilkS" user "Ref Des/Silkscreen Bottom")
		(1 "F.Mask" user "Board Geometry/Soldermask Top")
		(3 "B.Mask" user "Board Geometry/Soldermask Bottom")
		(17 "Dwgs.User" user "User.Drawings")
		(19 "Cmts.User" user "User.Comments")
		(21 "Eco1.User" user "User.Eco1")
		(23 "Eco2.User" user "User.Eco2")
		(25 "Edge.Cuts" user "Board Geometry/Outline")
		(27 "Margin" user)
		(31 "F.CrtYd" user "Package Geometry/Place Bound Top")
		(29 "B.CrtYd" user "Package Geometry/Place Bound Bottom")
		(35 "F.Fab" user "Ref Des/Assembly Top")
		(33 "B.Fab" user "Ref Des/Assembly Bottom")
	)
	(footprint ""
		(layer "B.Cu")
		(at 431.5841 -128.791208 -90)
		(property "Reference" "PR4235"
			(at 0 0 90)
			(layer "B.SilkS")
			(hide yes)
			(effects
				(font
					(size 1.27 1.27)
				)
				(justify mirror)
			)
		)
		(property "Value" ""
			(at 0 0 90)
			(layer "B.Fab")
			(effects
				(font
					(size 1.27 1.27)
				)
				(justify mirror)
			)
		)
		(duplicate_pad_numbers_are_jumpers no)
		(fp_line
			(start -0.7874 0.4064)
			(end 0.7874 0.4064)
			(stroke
				(width 0.1524)
				(type default)
			)
			(layer "B.SilkS")
		)
		(fp_line
			(start 0.7874 0.4064)
			(end 0.7874 -0.4064)
			(stroke
				(width 0.1524)
				(type default)
			)
			(layer "B.SilkS")
		)
		(fp_line
			(start -0.7874 -0.4064)
			(end -0.7874 0.4064)
			(stroke
				(width 0.1524)
				(type default)
			)
			(layer "B.SilkS")
		)
		(fp_line
			(start 0.7874 -0.4064)
			(end -0.7874 -0.4064)
			(stroke
				(width 0.1524)
				(type default)
			)
			(layer "B.SilkS")
		)
		(fp_line
			(start -0.67945 0.3048)
			(end -0.120396 0.3048)
			(stroke
				(width 0.1)
				(type default)
			)
			(layer "B.Fab")
		)
		(fp_line
			(start -0.120396 0.3048)
			(end -0.120396 0.2794)
			(stroke
				(width 0.1)
				(type default)
			)
			(layer "B.Fab")
		)
		(fp_line
			(start 0.12065 0.3048)
			(end 0.67945 0.3048)
			(stroke
				(width 0.1)
				(type default)
			)
			(layer "B.Fab")
		)
		(fp_line
			(start 0.67945 0.3048)
			(end 0.67945 -0.305054)
			(stroke
				(width 0.1)
				(type default)
			)
			(layer "B.Fab")
		)
		(fp_line
			(start -0.120396 0.2794)
			(end 0.12065 0.2794)
			(stroke
				(width 0.1)
				(type default)
			)
			(layer "B.Fab")
		)
		(fp_line
			(start 0.12065 0.2794)
			(end 0.12065 0.3048)
			(stroke
				(width 0.1)
				(type default)
			)
			(layer "B.Fab")
		)
		(fp_line
			(start -0.12065 -0.2794)
			(end -0.12065 -0.3048)
			(stroke
				(width 0.1)
				(type default)
			)
			(layer "B.Fab")
		)
		(fp_line
			(start 0.12065 -0.2794)
			(end -0.12065 -0.2794)
			(stroke
				(width 0.1)
				(type default)
			)
			(layer "B.Fab")
		)
		(fp_line
			(start -0.67945 -0.3048)
			(end -0.67945 0.3048)
			(stroke
				(width 0.1)
				(type default)
			)
			(layer "B.Fab")
		)
		(fp_line
			(start -0.12065 -0.3048)
			(end -0.67945 -0.3048)
			(stroke
				(width 0.1)
				(type default)
			)
			(layer "B.Fab")
		)
		(fp_line
			(start 0.12065 -0.305054)
			(end 0.12065 -0.2794)
			(stroke
				(width 0.1)
				(type default)
			)
			(layer "B.Fab")
		)
		(fp_line
			(start 0.67945 -0.305054)
			(end 0.12065 -0.305054)
			(stroke
				(width 0.1)
				(type default)
			)
			(layer "B.Fab")
		)
		(pad "1" smd circle
			(at 0.40005 0 90)
			(size 0 0)
			(layers "B.Cu" "B.Mask" "B.Paste")
			(net "NC_PVCCD_HV_CPU0_ACSP7")
		)
		(pad "2" smd circle
			(at -0.40005 0 90)
			(size 0 0)
			(layers "B.Cu" "B.Mask" "B.Paste")
			(net "GND")
		)
	)
	(footprint ""
		(layer "B.Cu")
		(at 302.300132 -55.971948 180)
		(property "Reference" "C1231"
			(at 0 0 0)
			(layer "B.SilkS")
			(hide yes)
			(effects
				(font
					(size 1.27 1.27)
				)
				(justify mirror)
			)
		)
		(property "Value" ""
			(at 0 0 0)
			(layer "B.Fab")
			(effects
				(font
					(size 1.27 1.27)
				)
				(justify mirror)
			)
		)
		(duplicate_pad_numbers_are_jumpers no)
		(fp_line
			(start 0.7874 0.4064)
			(end 0.7874 -0.4064)
			(stroke
				(width 0.1524)
				(type default)
			)
			(layer "B.SilkS")
		)
		(fp_line
			(start 0.7874 -0.4064)
			(end -0.7874 -0.4064)
			(stroke
				(width 0.1524)
				(type default)
			)
			(layer "B.SilkS")
		)
		(fp_line
			(start -0.7874 0.4064)
			(end 0.7874 0.4064)
			(stroke
				(width 0.1524)
				(type default)
			)
			(layer "B.SilkS")
		)
		(fp_line
			(start -0.7874 -0.4064)
			(end -0.7874 0.4064)
			(stroke
				(width 0.1524)
				(type default)
			)
			(layer "B.SilkS")
		)
		(fp_line
			(start 0.67945 0.3048)
			(end 0.67945 -0.305054)
			(stroke
				(width 0.1)
				(type default)
			)
			(layer "B.Fab")
		)
		(fp_line
			(start 0.67945 -0.305054)
			(end 0.12065 -0.305054)
			(stroke
				(width 0.1)
				(type default)
			)
			(layer "B.Fab")
		)
		(fp_line
			(start 0.12065 0.3048)
			(end 0.67945 0.3048)
			(stroke
				(width 0.1)
				(type default)
			)
			(layer "B.Fab")
		)
		(fp_line
			(start 0.12065 0.2794)
			(end 0.12065 0.3048)
			(stroke
				(width 0.1)
				(type default)
			)
			(layer "B.Fab")
		)
		(fp_line
			(start 0.12065 -0.2794)
			(end -0.12065 -0.2794)
			(stroke
				(width 0.1)
				(type default)
			)
			(layer "B.Fab")
		)
		(fp_line
			(start 0.12065 -0.305054)
			(end 0.12065 -0.2794)
			(stroke
				(width 0.1)
				(type default)
			)
			(layer "B.Fab")
		)
		(fp_line
			(start -0.120396 0.3048)
			(end -0.120396 0.2794)
			(stroke
				(width 0.1)
				(type default)
			)
			(layer "B.Fab")
		)
		(fp_line
			(start -0.120396 0.2794)
			(end 0.12065 0.2794)
			(stroke
				(width 0.1)
				(type default)
			)
			(layer "B.Fab")
		)
		(fp_line
			(start -0.12065 -0.2794)
			(end -0.12065 -0.3048)
			(stroke
				(width 0.1)
				(type default)
			)
			(layer "B.Fab")
		)
		(fp_line
			(start -0.12065 -0.3048)
			(end -0.67945 -0.3048)
			(stroke
				(width 0.1)
				(type default)
			)
			(layer "B.Fab")
		)
		(fp_line
			(start -0.67945 0.3048)
			(end -0.120396 0.3048)
			(stroke
				(width 0.1)
				(type default)
			)
			(layer "B.Fab")
		)
		(fp_line
			(start -0.67945 -0.3048)
			(end -0.67945 0.3048)
			(stroke
				(width 0.1)
				(type default)
			)
			(layer "B.Fab")
		)
		(pad "1" smd circle
			(at 0.40005 0)
			(size 0 0)
			(layers "B.Cu" "B.Mask" "B.Paste")
			(net "P1V05_PCH_AUX")
		)
		(pad "2" smd circle
			(at -0.40005 0)
			(size 0 0)
			(layers "B.Cu" "B.Mask" "B.Paste")
			(net "GND")
		)
	)
	(footprint ""
		(layer "B.Cu")
		(at 477.81591 -427.280578 180)
		(property "Reference" "DB15"
			(at 2.527554 -8.29691 270)
			(unlocked yes)
			(layer "B.SilkS")
			(effects
				(font
					(size 0.7874 0.5842)
					(thickness 0.1524)
				)
				(justify left mirror)
			)
		)
		(property "Value" ""
			(at 0 0 0)
			(layer "B.Fab")
			(effects
				(font
					(size 1.27 1.27)
				)
				(justify mirror)
			)
		)
		(duplicate_pad_numbers_are_jumpers no)
		(fp_line
			(start 3.330702 -4.771136)
			(end -3.330702 -4.771136)
			(stroke
				(width 0.1524)
				(type default)
			)
			(layer "B.SilkS")
		)
		(fp_line
			(start 0 4.011168)
			(end 3.330702 -4.771136)
			(stroke
				(width 0.1524)
				(type default)
			)
			(layer "B.SilkS")
		)
		(fp_line
			(start -3.330702 -4.771136)
			(end 0 4.011168)
			(stroke
				(width 0.1524)
				(type default)
			)
			(layer "B.SilkS")
		)
		(fp_line
			(start 3.330702 -4.771136)
			(end -3.330702 -4.771136)
			(stroke
				(width 0.1)
				(type default)
			)
			(layer "B.Fab")
		)
		(fp_line
			(start 0 4.011168)
			(end 3.330702 -4.771136)
			(stroke
				(width 0.1)
				(type default)
			)
			(layer "B.Fab")
		)
		(fp_line
			(start -3.330702 -4.771136)
			(end 0 4.011168)
			(stroke
				(width 0.1)
				(type default)
			)
			(layer "B.Fab")
		)
		(pad "1" thru_hole circle
			(at 0 0)
			(size 2.159 2.159)
			(drill 1.7018)
			(layers "*.Cu" "*.Mask")
			(remove_unused_layers no)
			(net "T1_GND")
			(clearance 0.0254)
			(thermal_gap 0.0254)
		)
		(pad "2" thru_hole circle
			(at 1.27 -3.348736)
			(size 2.159 2.159)
			(drill 1.7018)
			(layers "*.Cu" "*.Mask")
			(remove_unused_layers no)
			(net "TDR_SE_50_OHM_IN5")
			(clearance 0.0254)
			(thermal_gap 0.0254)
		)
		(pad "3" thru_hole circle
			(at -1.27 -3.348736)
			(size 2.159 2.159)
			(drill 1.7018)
			(layers "*.Cu" "*.Mask")
			(remove_unused_layers no)
			(net "TDR_SE_50_OHM_IN5")
			(clearance 0.0254)
			(thermal_gap 0.0254)
		)
	)
)
